(kicad_pcb
	(version 20260206)
	(generator "pcbnew")
	(generator_version "10.0")
	(general
		(thickness 1.6)
		(legacy_teardrops no)
	)
	(paper "A4")
	(title_block
		(title "timecard-production-celestica-r4006 — R4006-B0001-02_R01.brd")
		(comment 1 "Time Appliance Project (Time Card) / footprints 546-547 of 1113")
	)
	(layers
		(0 "F.Cu" signal "TOP")
		(4 "In1.Cu" signal "L02_GND1")
		(6 "In2.Cu" signal "L03_SIG1")
		(8 "In3.Cu" signal "L04_GND2")
		(10 "In4.Cu" signal "L05_VCC1")
		(12 "In5.Cu" signal "L06_VCC2")
		(14 "In6.Cu" signal "L07_GND3")
		(16 "In7.Cu" signal "L08_SIG2")
		(18 "In8.Cu" signal "L09_GND4")
		(2 "B.Cu" signal "BOTTOM")
		(9 "F.Adhes" user "F.Adhesive")
		(11 "B.Adhes" user "B.Adhesive")
		(13 "F.Paste" user "Package Geometry/Pastemask Top")
		(15 "B.Paste" user "Package Geometry/Pastemask Bottom")
		(5 "F.SilkS" user "Ref Des/Silkscreen Top")
		(7 "B.SilkS" user "Ref Des/Silkscreen Bottom")
		(1 "F.Mask" user "Board Geometry/Soldermask Top")
		(3 "B.Mask" user "Board Geometry/Soldermask Bottom")
		(17 "Dwgs.User" user "User.Drawings")
		(19 "Cmts.User" user "User.Comments")
		(21 "Eco1.User" user "User.Eco1")
		(23 "Eco2.User" user "User.Eco2")
		(25 "Edge.Cuts" user "Board Geometry/Outline")
		(27 "Margin" user)
		(31 "F.CrtYd" user "Package Geometry/Place Bound Top")
		(29 "B.CrtYd" user "Package Geometry/Place Bound Bottom")
		(35 "F.Fab" user "Ref Des/Assembly Top")
		(33 "B.Fab" user "Ref Des/Assembly Bottom")
	)
	(footprint ""
		(layer "F.Cu")
		(at 93.853 -65.278 -90)
		(property "Reference" "U34"
			(at -1.23063 -3.683 0)
			(unlocked yes)
			(layer "F.SilkS")
			(effects
				(font
					(size 0.7874 0.5842)
					(thickness 0.1524)
				)
			)
		)
		(property "Value" ""
			(at 0 0 270)
			(layer "F.Fab")
			(effects
				(font
					(size 1.27 1.27)
				)
			)
		)
		(property "Device Type" "TPS3808G18DBVR_SOT23_6-G222-00A"
			(at 0.1016 2.54127 270)
			(unlocked yes)
			(layer "F.Fab")
			(hide yes)
			(effects
				(font
					(size 0.7874 0.5842)
					(thickness 0.1524)
				)
			)
		)
		(property "User Part Number" "PARTNUM*"
			(at 0.1016 3.45567 270)
			(unlocked yes)
			(layer "Cmts.User")
			(hide yes)
			(effects
				(font
					(size 0.7874 0.5842)
					(thickness 0.1524)
				)
			)
		)
		(duplicate_pad_numbers_are_jumpers no)
		(fp_line
			(start -1.0541 1.704086)
			(end 1.0541 1.704086)
			(stroke
				(width 0.1)
				(type default)
			)
			(layer "F.SilkS")
		)
		(fp_line
			(start 1.0541 1.704086)
			(end 1.0541 1.45796)
			(stroke
				(width 0.1)
				(type default)
			)
			(layer "F.SilkS")
		)
		(fp_line
			(start -2.286 1.45796)
			(end -1.0541 1.45796)
			(stroke
				(width 0.1)
				(type default)
			)
			(layer "F.SilkS")
		)
		(fp_line
			(start -1.0541 1.45796)
			(end -1.0541 1.704086)
			(stroke
				(width 0.1)
				(type default)
			)
			(layer "F.SilkS")
		)
		(fp_line
			(start 1.0541 1.45796)
			(end 2.286 1.45796)
			(stroke
				(width 0.1)
				(type default)
			)
			(layer "F.SilkS")
		)
		(fp_line
			(start 2.286 1.45796)
			(end 2.286 -1.45796)
			(stroke
				(width 0.1)
				(type default)
			)
			(layer "F.SilkS")
		)
		(fp_line
			(start -2.286 -1.45796)
			(end -2.286 1.45796)
			(stroke
				(width 0.1)
				(type default)
			)
			(layer "F.SilkS")
		)
		(fp_line
			(start -1.0541 -1.45796)
			(end -2.286 -1.45796)
			(stroke
				(width 0.1)
				(type default)
			)
			(layer "F.SilkS")
		)
		(fp_line
			(start 1.0541 -1.45796)
			(end 1.0541 -1.704086)
			(stroke
				(width 0.1)
				(type default)
			)
			(layer "F.SilkS")
		)
		(fp_line
			(start 2.286 -1.45796)
			(end 1.0541 -1.45796)
			(stroke
				(width 0.1)
				(type default)
			)
			(layer "F.SilkS")
		)
		(fp_line
			(start -1.0541 -1.704086)
			(end -1.0541 -1.45796)
			(stroke
				(width 0.1)
				(type default)
			)
			(layer "F.SilkS")
		)
		(fp_line
			(start 1.0541 -1.704086)
			(end -1.0541 -1.704086)
			(stroke
				(width 0.1)
				(type default)
			)
			(layer "F.SilkS")
		)
		(fp_poly
			(pts
				(arc
					(start -2.286 -2.286)
					(mid -2.286 -1.524)
					(end -2.286 -2.286)
				)
			)
			(stroke
				(width 0)
				(type default)
			)
			(fill yes)
			(layer "F.SilkS")
		)
		(fp_poly
			(pts
				(xy -2.54 -1.9558) (xy 2.54 -1.9558) (xy 2.54 1.9558) (xy -2.54 1.9558)
			)
			(stroke
				(width 0)
				(type default)
			)
			(fill no)
			(layer "F.CrtYd")
		)
		(fp_line
			(start -0.8001 1.450086)
			(end 0.8001 1.450086)
			(stroke
				(width 0.1)
				(type default)
			)
			(layer "F.Fab")
		)
		(fp_line
			(start -0.8001 1.450086)
			(end -0.599948 1.249934)
			(stroke
				(width 0.1)
				(type default)
			)
			(layer "F.Fab")
		)
		(fp_line
			(start 0.8001 1.450086)
			(end 0.599948 1.249934)
			(stroke
				(width 0.1)
				(type default)
			)
			(layer "F.Fab")
		)
		(fp_line
			(start 0.8001 1.450086)
			(end 0.8001 1.199896)
			(stroke
				(width 0.1)
				(type default)
			)
			(layer "F.Fab")
		)
		(fp_line
			(start -0.599948 1.249934)
			(end -0.599948 -1.249934)
			(stroke
				(width 0.1)
				(type default)
			)
			(layer "F.Fab")
		)
		(fp_line
			(start 0.599948 1.249934)
			(end -0.599948 1.249934)
			(stroke
				(width 0.1)
				(type default)
			)
			(layer "F.Fab")
		)
		(fp_line
			(start -1.500124 1.199896)
			(end -1.500124 0.700024)
			(stroke
				(width 0.1)
				(type default)
			)
			(layer "F.Fab")
		)
		(fp_line
			(start -0.8001 1.199896)
			(end -0.8001 1.450086)
			(stroke
				(width 0.1)
				(type default)
			)
			(layer "F.Fab")
		)
		(fp_line
			(start -0.700024 1.199896)
			(end -1.500124 1.199896)
			(stroke
				(width 0.1)
				(type default)
			)
			(layer "F.Fab")
		)
		(fp_line
			(start 0.700024 1.199896)
			(end 0.700024 0.700024)
			(stroke
				(width 0.1)
				(type default)
			)
			(layer "F.Fab")
		)
		(fp_line
			(start 1.500124 1.199896)
			(end 0.700024 1.199896)
			(stroke
				(width 0.1)
				(type default)
			)
			(layer "F.Fab")
		)
		(fp_line
			(start -1.500124 0.700024)
			(end -0.700024 0.700024)
			(stroke
				(width 0.1)
				(type default)
			)
			(layer "F.Fab")
		)
		(fp_line
			(start -0.700024 0.700024)
			(end -0.700024 1.199896)
			(stroke
				(width 0.1)
				(type default)
			)
			(layer "F.Fab")
		)
		(fp_line
			(start 0.700024 0.700024)
			(end 1.500124 0.700024)
			(stroke
				(width 0.1)
				(type default)
			)
			(layer "F.Fab")
		)
		(fp_line
			(start 1.500124 0.700024)
			(end 1.500124 1.199896)
			(stroke
				(width 0.1)
				(type default)
			)
			(layer "F.Fab")
		)
		(fp_line
			(start -1.500124 0.249936)
			(end -1.500124 -0.249936)
			(stroke
				(width 0.1)
				(type default)
			)
			(layer "F.Fab")
		)
		(fp_line
			(start -0.8001 0.249936)
			(end -0.8001 0.700024)
			(stroke
				(width 0.1)
				(type default)
			)
			(layer "F.Fab")
		)
		(fp_line
			(start -0.700024 0.249936)
			(end -1.500124 0.249936)
			(stroke
				(width 0.1)
				(type default)
			)
			(layer "F.Fab")
		)
		(fp_line
			(start 0.700024 0.249936)
			(end 0.8001 0.249936)
			(stroke
				(width 0.1)
				(type default)
			)
			(layer "F.Fab")
		)
		(fp_line
			(start 0.700024 0.249936)
			(end 0.700024 -0.249936)
			(stroke
				(width 0.1)
				(type default)
			)
			(layer "F.Fab")
		)
		(fp_line
			(start 0.8001 0.249936)
			(end 0.8001 0.700024)
			(stroke
				(width 0.1)
				(type default)
			)
			(layer "F.Fab")
		)
		(fp_line
			(start 1.500124 0.249936)
			(end 0.700024 0.249936)
			(stroke
				(width 0.1)
				(type default)
			)
			(layer "F.Fab")
		)
		(fp_line
			(start -1.500124 -0.249936)
			(end -0.700024 -0.249936)
			(stroke
				(width 0.1)
				(type default)
			)
			(layer "F.Fab")
		)
		(fp_line
			(start -0.700024 -0.249936)
			(end -0.700024 0.249936)
			(stroke
				(width 0.1)
				(type default)
			)
			(layer "F.Fab")
		)
		(fp_line
			(start 0.700024 -0.249936)
			(end 0.700024 0.249936)
			(stroke
				(width 0.1)
				(type default)
			)
			(layer "F.Fab")
		)
		(fp_line
			(start 0.700024 -0.249936)
			(end 1.500124 -0.249936)
			(stroke
				(width 0.1)
				(type default)
			)
			(layer "F.Fab")
		)
		(fp_line
			(start 0.8001 -0.249936)
			(end 0.700024 -0.249936)
			(stroke
				(width 0.1)
				(type default)
			)
			(layer "F.Fab")
		)
		(fp_line
			(start 1.500124 -0.249936)
			(end 1.500124 0.249936)
			(stroke
				(width 0.1)
				(type default)
			)
			(layer "F.Fab")
		)
		(fp_line
			(start -1.500124 -0.700024)
			(end -1.500124 -1.199896)
			(stroke
				(width 0.1)
				(type default)
			)
			(layer "F.Fab")
		)
		(fp_line
			(start -0.8001 -0.700024)
			(end -0.8001 -0.249936)
			(stroke
				(width 0.1)
				(type default)
			)
			(layer "F.Fab")
		)
		(fp_line
			(start -0.700024 -0.700024)
			(end -1.500124 -0.700024)
			(stroke
				(width 0.1)
				(type default)
			)
			(layer "F.Fab")
		)
		(fp_line
			(start 0.700024 -0.700024)
			(end 0.700024 -1.199896)
			(stroke
				(width 0.1)
				(type default)
			)
			(layer "F.Fab")
		)
		(fp_line
			(start 0.8001 -0.700024)
			(end 0.8001 -0.249936)
			(stroke
				(width 0.1)
				(type default)
			)
			(layer "F.Fab")
		)
		(fp_line
			(start 1.500124 -0.700024)
			(end 0.700024 -0.700024)
			(stroke
				(width 0.1)
				(type default)
			)
			(layer "F.Fab")
		)
		(fp_line
			(start -1.500124 -1.199896)
			(end -0.700024 -1.199896)
			(stroke
				(width 0.1)
				(type default)
			)
			(layer "F.Fab")
		)
		(fp_line
			(start -0.8001 -1.199896)
			(end -0.8001 -1.450086)
			(stroke
				(width 0.1)
				(type default)
			)
			(layer "F.Fab")
		)
		(fp_line
			(start -0.700024 -1.199896)
			(end -0.700024 -0.700024)
			(stroke
				(width 0.1)
				(type default)
			)
			(layer "F.Fab")
		)
		(fp_line
			(start 0.700024 -1.199896)
			(end 1.500124 -1.199896)
			(stroke
				(width 0.1)
				(type default)
			)
			(layer "F.Fab")
		)
		(fp_line
			(start 1.500124 -1.199896)
			(end 1.500124 -0.700024)
			(stroke
				(width 0.1)
				(type default)
			)
			(layer "F.Fab")
		)
		(fp_line
			(start -0.599948 -1.249934)
			(end 0.599948 -1.249934)
			(stroke
				(width 0.1)
				(type default)
			)
			(layer "F.Fab")
		)
		(fp_line
			(start -0.599948 -1.249934)
			(end -0.8001 -1.450086)
			(stroke
				(width 0.1)
				(type default)
			)
			(layer "F.Fab")
		)
		(fp_line
			(start 0.599948 -1.249934)
			(end 0.599948 1.249934)
			(stroke
				(width 0.1)
				(type default)
			)
			(layer "F.Fab")
		)
		(fp_line
			(start 0.599948 -1.249934)
			(end 0.8001 -1.450086)
			(stroke
				(width 0.1)
				(type default)
			)
			(layer "F.Fab")
		)
		(fp_line
			(start -0.8001 -1.450086)
			(end 0.8001 -1.450086)
			(stroke
				(width 0.1)
				(type default)
			)
			(layer "F.Fab")
		)
		(fp_line
			(start 0.8001 -1.450086)
			(end 0.8001 -1.199896)
			(stroke
				(width 0.1)
				(type default)
			)
			(layer "F.Fab")
		)
		(fp_poly
			(pts
				(arc
					(start -0.350012 -1.100074)
					(mid -0.350012 -0.799846)
					(end -0.350012 -1.100074)
				)
			)
			(stroke
				(width 0)
				(type default)
			)
			(fill yes)
			(layer "F.Fab")
		)
		(fp_text user "3"
			(at -2.25425 2.032 0)
			(unlocked yes)
			(layer "F.SilkS")
			(effects
				(font
					(size 0.635 0.4064)
					(thickness 0.1524)
				)
			)
		)
		(fp_text user "4"
			(at 3.02895 1.524 0)
			(unlocked yes)
			(layer "F.SilkS")
			(effects
				(font
					(size 0.635 0.4064)
					(thickness 0.1524)
				)
			)
		)
		(fp_text user "6"
			(at 2.69875 -1.905 0)
			(unlocked yes)
			(layer "F.SilkS")
			(effects
				(font
					(size 0.635 0.4064)
					(thickness 0.1524)
				)
			)
		)
		(fp_text user "4"
			(at 2.07137 1.778 0)
			(unlocked yes)
			(layer "F.Fab")
			(effects
				(font
					(size 0.7874 0.5842)
					(thickness 0.1524)
				)
			)
		)
		(fp_text user "3"
			(at -2.37363 1.524 0)
			(unlocked yes)
			(layer "F.Fab")
			(effects
				(font
					(size 0.7874 0.5842)
					(thickness 0.1524)
				)
			)
		)
		(fp_text user "6"
			(at 2.19837 -1.651 0)
			(unlocked yes)
			(layer "F.Fab")
			(effects
				(font
					(size 0.7874 0.5842)
					(thickness 0.1524)
				)
			)
		)
		(pad "1" smd rect
			(at -1.4351 -0.94996)
			(size 0.508 1.1938)
			(layers "F.Cu" "F.Mask" "F.Paste")
			(net "FPGA_IN_RST_DLY_N")
		)
		(pad "2" smd rect
			(at -1.4351 0)
			(size 0.508 1.1938)
			(layers "F.Cu" "F.Mask" "F.Paste")
			(net "SG")
		)
		(pad "3" smd rect
			(at -1.4351 0.94996)
			(size 0.508 1.1938)
			(layers "F.Cu" "F.Mask" "F.Paste")
			(net "PCIE_PERST_N")
		)
		(pad "4" smd rect
			(at 1.4351 0.94996)
			(size 0.508 1.1938)
			(layers "F.Cu" "F.Mask" "F.Paste")
			(net "UNNAMED_3_RESISTOR_I151_2")
		)
		(pad "5" smd rect
			(at 1.4351 0)
			(size 0.508 1.1938)
			(layers "F.Cu" "F.Mask" "F.Paste")
			(net "XP3R3V_FPGA")
		)
		(pad "6" smd rect
			(at 1.4351 -0.94996)
			(size 0.508 1.1938)
			(layers "F.Cu" "F.Mask" "F.Paste")
			(net "XP3R3V_FPGA")
		)
	)
	(footprint ""
		(layer "F.Cu")
		(at 100.2538 -69.215)
		(property "Reference" "R181"
			(at 2.8702 -0.08763 0)
			(unlocked yes)
			(layer "F.SilkS")
			(effects
				(font
					(size 0.7874 0.5842)
					(thickness 0.1524)
				)
			)
		)
		(property "Value" "VAL*"
			(at 0.02032 2.13233 0)
			(unlocked yes)
			(layer "F.Fab")
			(hide yes)
			(effects
				(font
					(size 0.7874 0.5842)
					(thickness 0.1524)
				)
			)
		)
		(property "Tolerance" "TOL*"
			(at 0.044704 3.05435 0)
			(unlocked yes)
			(layer "Cmts.User")
			(hide yes)
			(effects
				(font
					(size 0.7874 0.5842)
					(thickness 0.1524)
				)
			)
		)
		(property "User Part Number" "PARTNUM*"
			(at 0.02032 4.024884 0)
			(unlocked yes)
			(layer "Cmts.User")
			(hide yes)
			(effects
				(font
					(size 0.7874 0.5842)
					(thickness 0.1524)
				)
			)
		)
		(property "Device Type" "RESISTOR-G155-100R0-J0,0OHM,-"
			(at 0.008382 1.210564 0)
			(unlocked yes)
			(layer "F.Fab")
			(hide yes)
			(effects
				(font
					(size 0.7874 0.5842)
					(thickness 0.1524)
				)
			)
		)
		(duplicate_pad_numbers_are_jumpers no)
		(fp_line
			(start -1.143 -0.5588)
			(end -1.143 0.5588)
			(stroke
				(width 0.1)
				(type default)
			)
			(layer "F.SilkS")
		)
		(fp_line
			(start -1.143 0.5588)
			(end 1.143 0.5588)
			(stroke
				(width 0.1)
				(type default)
			)
			(layer "F.SilkS")
		)
		(fp_line
			(start 1.143 -0.5588)
			(end -1.143 -0.5588)
			(stroke
				(width 0.1)
				(type default)
			)
			(layer "F.SilkS")
		)
		(fp_line
			(start 1.143 0.5588)
			(end 1.143 -0.5588)
			(stroke
				(width 0.1)
				(type default)
			)
			(layer "F.SilkS")
		)
		(fp_rect
			(start -1.143 -0.5588)
			(end 1.143 0.5588)
			(stroke
				(width 0)
				(type default)
			)
			(fill no)
			(layer "F.CrtYd")
		)
		(fp_line
			(start -0.508 -0.3048)
			(end -0.508 0.3048)
			(stroke
				(width 0.1)
				(type default)
			)
			(layer "F.Fab")
		)
		(fp_line
			(start -0.508 0.3048)
			(end 0.508 0.3048)
			(stroke
				(width 0.1)
				(type default)
			)
			(layer "F.Fab")
		)
		(fp_line
			(start 0.508 -0.3048)
			(end -0.508 -0.3048)
			(stroke
				(width 0.1)
				(type default)
			)
			(layer "F.Fab")
		)
		(fp_line
			(start 0.508 0.3048)
			(end 0.508 -0.3048)
			(stroke
				(width 0.1)
				(type default)
			)
			(layer "F.Fab")
		)
		(pad "1" smd rect
			(at -0.5334 0)
			(size 0.7112 0.6096)
			(layers "F.Cu" "F.Mask" "F.Paste")
			(net "XP1R2V_PG_R")
		)
		(pad "2" smd rect
			(at 0.5334 0)
			(size 0.7112 0.6096)
			(layers "F.Cu" "F.Mask" "F.Paste")
			(net "XP1R2V_FPGA_PG")
		)
		(zone
			(layer "F.Cu")
			(hatch none 0.5)
			(connect_pads
				(clearance 0)
			)
			(min_thickness 0.25)
			(keepout
				(tracks allowed)
				(vias not_allowed)
				(pads allowed)
				(copperpour not_allowed)
				(footprints allowed)
			)
			(placement
				(enabled no)
				(sheetname "")
			)
			(fill
				(thermal_gap 0.5)
				(thermal_bridge_width 0.5)
				(island_removal_mode 0)
			)
			(polygon
				(pts
					(xy 100.1776 -69.5198) (xy 100.1776 -68.9102) (xy 100.33 -68.9102) (xy 100.33 -69.5198)
				)
			)
		)
	)
)
